(kicad_pcb
	(version 20221018)
	(generator pcbnew)
	(general
    (thickness 1.656)
  )
	(paper "A4")
	(title_block
    (title "SDI-MIPI Bridge")
    (date "2023-08-09")
    (rev "1.3.4")
    (company "Antmicro")
		(comment 9 "footprints 71-79 of 190")
	)
	(layers
    (0 "F.Cu" signal)
    (1 "In1.Cu" power)
    (2 "In2.Cu" power)
    (3 "In3.Cu" signal)
    (4 "In4.Cu" signal)
    (31 "B.Cu" signal)
    (32 "B.Adhes" user "B.Adhesive")
    (33 "F.Adhes" user "F.Adhesive")
    (34 "B.Paste" user)
    (35 "F.Paste" user)
    (36 "B.SilkS" user "B.Silkscreen")
    (37 "F.SilkS" user "F.Silkscreen")
    (38 "B.Mask" user)
    (39 "F.Mask" user)
    (40 "Dwgs.User" user "User.Drawings")
    (41 "Cmts.User" user "User.Comments")
    (42 "Eco1.User" user "User.Eco1")
    (43 "Eco2.User" user "User.Eco2")
    (44 "Edge.Cuts" user)
    (45 "Margin" user)
    (46 "B.CrtYd" user "B.Courtyard")
    (47 "F.CrtYd" user "F.Courtyard")
    (48 "B.Fab" user)
    (49 "F.Fab" user)
  )
	(footprint "sdi-mipi-bridge-footprints:oshw-logo"
		(layer "F.Cu")
    (at 109.7 99.9)
    (descr "OSHW Logo")
    (tags "OSHW Logo")
    (property "Author" "Antmicro")
    (property "License" "Apache-2.0")
    (property "MPN" "")
    (property "Manufacturer" "")
    (property "Sheetfile" "sdi-mipi-bridge.kicad_sch")
    (property "Sheetname" "")
    (attr smd)
    (fp_text reference "N2" (at 0 -4.4) (layer "F.SilkS") hide
        (effects (font (size 0.65 0.65) (thickness 0.15)) (justify left bottom))
    )
    (fp_text value "oshw_logo" (at 0 -3.4) (layer "F.Fab") hide
        (effects (font (size 0.7 0.7) (thickness 0.15)) (justify left bottom))
    )
  )
	(footprint "sdi-mipi-bridge-footprints:R_0402_1005Metric" (layer "F.Cu")
    (at 127 107.4 -90)
    (descr "Resistor SMD 0402")
    (tags "resistor SMD 0402")
    (property "Author" "Antmicro")
    (property "License" "Apache-2.0")
    (property "MPN" "CR0402-FX-1000GLF")
    (property "Manufacturer" "Bourns")
    (property "Sheetfile" "sdi-mipi-bridge.kicad_sch")
    (property "Sheetname" "")
    (property "Tolerance" "1%")
    (property "Val" "100R")
    (property "ki_description" "100R resistor in 0402 package with 1% tolerance")
    (attr smd)
    (fp_text reference "R93" (at 0.9 0.6 -90) (layer "F.SilkS")
        (effects (font (size 0.65 0.65) (thickness 0.15)) (justify left bottom))
    )
    (fp_text value "R_100R_0402" (at 0 1.4 -90) (layer "F.Fab") hide
        (effects (font (size 0.7 0.7) (thickness 0.15)) (justify left bottom))
    )
    (fp_text user "Author: Antmicro" (at -0.95 4.169 -90) (layer "F.Fab") hide
        (effects (font (size 0.7 0.7) (thickness 0.15)) (justify left bottom))
    )
    (fp_text user "License: Apache-2.0" (at -0.95 5.169 -90) (layer "F.Fab") hide
        (effects (font (size 0.7 0.7) (thickness 0.15)) (justify left bottom))
    )
    (fp_text user "${REFERENCE}" (at -0.95 3.168 -90) (layer "F.Fab") hide
        (effects (font (size 0.7 0.7) (thickness 0.15)) (justify left bottom))
    )
    (fp_rect (start -0.93 -0.47) (end 0.93 0.47)
      (stroke (width 0.05) (type solid)) (fill none) (layer "F.CrtYd"))
    (fp_rect (start -0.5 -0.25) (end 0.5 0.25)
      (stroke (width 0.15) (type solid)) (fill none) (layer "F.Fab"))
    (pad "1" smd roundrect (at -0.485 0 270) (size 0.59 0.64) (layers "F.Cu" "F.Paste" "F.Mask") (roundrect_rratio 0.25)
      (net 91 "Net-(D4-Pad1)") (pintype "passive"))
    (pad "2" smd roundrect (at 0.485 0 270) (size 0.59 0.64) (layers "F.Cu" "F.Paste" "F.Mask") (roundrect_rratio 0.25)
      (net 106 "/USER_LED") (pintype "passive"))
  )
	(footprint "sdi-mipi-bridge-footprints:LED_0603_1608Metric_G" (layer "F.Cu")
    (at 127 104.4 90)
    (descr "LED SMD 0603 Green")
    (tags "LED SMD 0603 Green")
    (property "Author" "Antmicro")
    (property "License" "Apache-2.0")
    (property "MPN" "LG L29K-G2J1-24-Z")
    (property "Manufacturer" "Osram")
    (property "Sheetfile" "sdi-mipi-bridge.kicad_sch")
    (property "Sheetname" "")
    (attr smd)
    (fp_text reference "D4" (at 0.2 -0.7 90) (layer "F.SilkS")
        (effects (font (size 0.65 0.65) (thickness 0.15)) (justify left bottom))
    )
    (fp_text value "LED_G_0603_LG_L29K-G2J1-24-Z" (at 0 1.6 90) (layer "F.Fab") hide
        (effects (font (size 0.7 0.7) (thickness 0.15)) (justify left bottom))
    )
    (fp_text user "License: Apache-2.0" (at -1.31 5.769 90) (layer "F.Fab") hide
        (effects (font (size 0.7 0.7) (thickness 0.15)) (justify left bottom))
    )
    (fp_text user "${REFERENCE}" (at -1.31 3.769 90) (layer "F.Fab") hide
        (effects (font (size 0.7 0.7) (thickness 0.15)) (justify left bottom))
    )
    (fp_text user "Author: Antmicro" (at -1.31 4.769 90) (layer "F.Fab") hide
        (effects (font (size 0.7 0.7) (thickness 0.15)) (justify left bottom))
    )
    (fp_line (start -0.27 -0.35) (end 0.27 -0.35)
      (stroke (width 0.15) (type solid)) (layer "F.SilkS"))
    (fp_line (start -0.27 0.351) (end 0.27 0.351)
      (stroke (width 0.15) (type solid)) (layer "F.SilkS"))
    (fp_line (start -0.106328 -0.200008) (end -0.106328 0.199992)
      (stroke (width 0.1) (type solid)) (layer "F.SilkS"))
    (fp_line (start -0.106328 -0.200008) (end 0.093672 -0.000008)
      (stroke (width 0.1) (type solid)) (layer "F.SilkS"))
    (fp_line (start -0.106328 -0.000008) (end -0.29 0)
      (stroke (width 0.1) (type solid)) (layer "F.SilkS"))
    (fp_line (start 0.093672 -0.200008) (end 0.093672 0.199992)
      (stroke (width 0.1) (type solid)) (layer "F.SilkS"))
    (fp_line (start 0.093672 -0.000008) (end -0.106328 0.199992)
      (stroke (width 0.1) (type solid)) (layer "F.SilkS"))
    (fp_line (start 0.093672 -0.000008) (end 0.293672 -0.000008)
      (stroke (width 0.1) (type solid)) (layer "F.SilkS"))
    (fp_line (start 1.25 0.32) (end 1.25 -0.32)
      (stroke (width 0.15) (type solid)) (layer "F.SilkS"))
    (fp_rect (start 1.26 0.65) (end -1.26 -0.65)
      (stroke (width 0.05) (type solid)) (fill none) (layer "F.CrtYd"))
    (fp_line (start -0.599 0) (end -0.201 0)
      (stroke (width 0.15) (type solid)) (layer "F.Fab"))
    (fp_line (start -0.201 -0.2) (end -0.201 0)
      (stroke (width 0.15) (type solid)) (layer "F.Fab"))
    (fp_line (start -0.201 0) (end -0.201 0.202)
      (stroke (width 0.15) (type solid)) (layer "F.Fab"))
    (fp_line (start -0.201 0.202) (end 0.101 0)
      (stroke (width 0.15) (type solid)) (layer "F.Fab"))
    (fp_line (start 0.101 0) (end -0.201 -0.2)
      (stroke (width 0.15) (type solid)) (layer "F.Fab"))
    (fp_line (start 0.199 -0.2) (end 0.199 -0.1)
      (stroke (width 0.15) (type solid)) (layer "F.Fab"))
    (fp_line (start 0.199 0) (end 0.597 0)
      (stroke (width 0.15) (type solid)) (layer "F.Fab"))
    (fp_line (start 0.199 0.202) (end 0.199 -0.1)
      (stroke (width 0.15) (type solid)) (layer "F.Fab"))
    (fp_rect (start -0.848 -0.4) (end 0.85 0.402)
      (stroke (width 0.15) (type solid)) (fill none) (layer "F.Fab"))
    (pad "1" smd rect (at -0.75 0 270) (size 0.8 0.8) (layers "F.Cu" "F.Paste" "F.Mask")
      (net 91 "Net-(D4-Pad1)") (pintype "passive"))
    (pad "2" smd rect (at 0.75 0 270) (size 0.8 0.8) (layers "F.Cu" "F.Paste" "F.Mask")
      (net 1 "GNDREF") (pinfunction "2") (pintype "passive"))
  )
	(footprint "sdi-mipi-bridge-footprints:R_0402_1005Metric" (layer "F.Cu")
    (at 129 107.4 -90)
    (descr "Resistor SMD 0402")
    (tags "resistor SMD 0402")
    (property "Author" "Antmicro")
    (property "License" "Apache-2.0")
    (property "MPN" "CR0402-FX-1000GLF")
    (property "Manufacturer" "Bourns")
    (property "Sheetfile" "sdi-mipi-bridge.kicad_sch")
    (property "Sheetname" "")
    (property "Tolerance" "1%")
    (property "Val" "100R")
    (property "ki_description" "100R resistor in 0402 package with 1% tolerance")
    (attr smd)
    (fp_text reference "R33" (at 0.9 -3.3 -90) (layer "F.SilkS")
        (effects (font (size 0.65 0.65) (thickness 0.15)) (justify left bottom))
    )
    (fp_text value "R_100R_0402" (at 0 1.4 -90) (layer "F.Fab") hide
        (effects (font (size 0.7 0.7) (thickness 0.15)) (justify left bottom))
    )
    (fp_text user "${REFERENCE}" (at -0.95 3.168 -90) (layer "F.Fab") hide
        (effects (font (size 0.7 0.7) (thickness 0.15)) (justify left bottom))
    )
    (fp_text user "License: Apache-2.0" (at -0.95 5.169 -90) (layer "F.Fab") hide
        (effects (font (size 0.7 0.7) (thickness 0.15)) (justify left bottom))
    )
    (fp_text user "Author: Antmicro" (at -0.95 4.169 -90) (layer "F.Fab") hide
        (effects (font (size 0.7 0.7) (thickness 0.15)) (justify left bottom))
    )
    (fp_rect (start -0.93 -0.47) (end 0.93 0.47)
      (stroke (width 0.05) (type solid)) (fill none) (layer "F.CrtYd"))
    (fp_rect (start -0.5 -0.25) (end 0.5 0.25)
      (stroke (width 0.15) (type solid)) (fill none) (layer "F.Fab"))
    (pad "1" smd roundrect (at -0.485 0 270) (size 0.59 0.64) (layers "F.Cu" "F.Paste" "F.Mask") (roundrect_rratio 0.25)
      (net 56 "Net-(D1-Pad1)") (pintype "passive"))
    (pad "2" smd roundrect (at 0.485 0 270) (size 0.59 0.64) (layers "F.Cu" "F.Paste" "F.Mask") (roundrect_rratio 0.25)
      (net 20 "/LOCKED") (pintype "passive"))
  )
	(footprint "sdi-mipi-bridge-footprints:LED_0603_1608Metric_G" (layer "F.Cu")
    (at 129 104.4 90)
    (descr "LED SMD 0603 Green")
    (tags "LED SMD 0603 Green")
    (property "Author" "Antmicro")
    (property "License" "Apache-2.0")
    (property "MPN" "LG L29K-G2J1-24-Z")
    (property "Manufacturer" "Osram")
    (property "Sheetfile" "sdi-mipi-bridge.kicad_sch")
    (property "Sheetname" "")
    (attr smd)
    (fp_text reference "D1" (at 0.2 -0.7 90) (layer "F.SilkS")
        (effects (font (size 0.65 0.65) (thickness 0.15)) (justify left bottom))
    )
    (fp_text value "LED_G_0603_LG_L29K-G2J1-24-Z" (at 0 1.6 90) (layer "F.Fab") hide
        (effects (font (size 0.7 0.7) (thickness 0.15)) (justify left bottom))
    )
    (fp_text user "License: Apache-2.0" (at -1.31 5.769 90) (layer "F.Fab") hide
        (effects (font (size 0.7 0.7) (thickness 0.15)) (justify left bottom))
    )
    (fp_text user "${REFERENCE}" (at -1.31 3.769 90) (layer "F.Fab") hide
        (effects (font (size 0.7 0.7) (thickness 0.15)) (justify left bottom))
    )
    (fp_text user "Author: Antmicro" (at -1.31 4.769 90) (layer "F.Fab") hide
        (effects (font (size 0.7 0.7) (thickness 0.15)) (justify left bottom))
    )
    (fp_line (start -0.27 -0.35) (end 0.27 -0.35)
      (stroke (width 0.15) (type solid)) (layer "F.SilkS"))
    (fp_line (start -0.27 0.351) (end 0.27 0.351)
      (stroke (width 0.15) (type solid)) (layer "F.SilkS"))
    (fp_line (start -0.106328 -0.200008) (end -0.106328 0.199992)
      (stroke (width 0.1) (type solid)) (layer "F.SilkS"))
    (fp_line (start -0.106328 -0.200008) (end 0.093672 -0.000008)
      (stroke (width 0.1) (type solid)) (layer "F.SilkS"))
    (fp_line (start -0.106328 -0.000008) (end -0.29 0)
      (stroke (width 0.1) (type solid)) (layer "F.SilkS"))
    (fp_line (start 0.093672 -0.200008) (end 0.093672 0.199992)
      (stroke (width 0.1) (type solid)) (layer "F.SilkS"))
    (fp_line (start 0.093672 -0.000008) (end -0.106328 0.199992)
      (stroke (width 0.1) (type solid)) (layer "F.SilkS"))
    (fp_line (start 0.093672 -0.000008) (end 0.293672 -0.000008)
      (stroke (width 0.1) (type solid)) (layer "F.SilkS"))
    (fp_line (start 1.25 0.32) (end 1.25 -0.32)
      (stroke (width 0.15) (type solid)) (layer "F.SilkS"))
    (fp_rect (start 1.26 0.65) (end -1.26 -0.65)
      (stroke (width 0.05) (type solid)) (fill none) (layer "F.CrtYd"))
    (fp_line (start -0.599 0) (end -0.201 0)
      (stroke (width 0.15) (type solid)) (layer "F.Fab"))
    (fp_line (start -0.201 -0.2) (end -0.201 0)
      (stroke (width 0.15) (type solid)) (layer "F.Fab"))
    (fp_line (start -0.201 0) (end -0.201 0.202)
      (stroke (width 0.15) (type solid)) (layer "F.Fab"))
    (fp_line (start -0.201 0.202) (end 0.101 0)
      (stroke (width 0.15) (type solid)) (layer "F.Fab"))
    (fp_line (start 0.101 0) (end -0.201 -0.2)
      (stroke (width 0.15) (type solid)) (layer "F.Fab"))
    (fp_line (start 0.199 -0.2) (end 0.199 -0.1)
      (stroke (width 0.15) (type solid)) (layer "F.Fab"))
    (fp_line (start 0.199 0) (end 0.597 0)
      (stroke (width 0.15) (type solid)) (layer "F.Fab"))
    (fp_line (start 0.199 0.202) (end 0.199 -0.1)
      (stroke (width 0.15) (type solid)) (layer "F.Fab"))
    (fp_rect (start -0.848 -0.4) (end 0.85 0.402)
      (stroke (width 0.15) (type solid)) (fill none) (layer "F.Fab"))
    (pad "1" smd rect (at -0.75 0 270) (size 0.8 0.8) (layers "F.Cu" "F.Paste" "F.Mask")
      (net 56 "Net-(D1-Pad1)") (pintype "passive"))
    (pad "2" smd rect (at 0.75 0 270) (size 0.8 0.8) (layers "F.Cu" "F.Paste" "F.Mask")
      (net 1 "GNDREF") (pinfunction "2") (pintype "passive"))
  )
	(footprint "sdi-mipi-bridge-footprints:R_0402_1005Metric" (layer "F.Cu")
    (at 159.8 105.9 180)
    (descr "Resistor SMD 0402")
    (tags "resistor SMD 0402")
    (property "Author" "Antmicro")
    (property "Current" "1A")
    (property "License" "Apache-2.0")
    (property "MPN" "ERJ2GE0R00X")
    (property "Manufacturer" "Panasonic")
    (property "Sheetfile" "sdi-mipi-bridge.kicad_sch")
    (property "Sheetname" "")
    (property "Tolerance" "")
    (property "Val" "0R")
    (property "ki_description" "0R resistor in 0402 package with unspecified tolerance")
    (attr smd)
    (fp_text reference "R92" (at 1.6 0.7 180) (layer "F.SilkS")
        (effects (font (size 0.65 0.65) (thickness 0.15)) (justify left bottom))
    )
    (fp_text value "R_0R_0402" (at 0 1.4 180) (layer "F.Fab") hide
        (effects (font (size 0.7 0.7) (thickness 0.15)) (justify left bottom))
    )
    (fp_text user "${REFERENCE}" (at -0.95 3.168 180) (layer "F.Fab") hide
        (effects (font (size 0.7 0.7) (thickness 0.15)) (justify left bottom))
    )
    (fp_text user "Author: Antmicro" (at -0.95 4.169 180) (layer "F.Fab") hide
        (effects (font (size 0.7 0.7) (thickness 0.15)) (justify left bottom))
    )
    (fp_text user "License: Apache-2.0" (at -0.95 5.169 180) (layer "F.Fab") hide
        (effects (font (size 0.7 0.7) (thickness 0.15)) (justify left bottom))
    )
    (fp_rect (start -0.93 -0.47) (end 0.93 0.47)
      (stroke (width 0.05) (type solid)) (fill none) (layer "F.CrtYd"))
    (fp_rect (start -0.5 -0.25) (end 0.5 0.25)
      (stroke (width 0.15) (type solid)) (fill none) (layer "F.Fab"))
    (pad "1" smd roundrect (at -0.485 0 180) (size 0.59 0.64) (layers "F.Cu" "F.Paste" "F.Mask") (roundrect_rratio 0.25)
      (net 136 "Net-(J3-Pad47)") (pintype "passive"))
    (pad "2" smd roundrect (at 0.485 0 180) (size 0.59 0.64) (layers "F.Cu" "F.Paste" "F.Mask") (roundrect_rratio 0.25)
      (net 6 "+3V3") (pintype "passive"))
  )
	(footprint "sdi-mipi-bridge-footprints:Mount-hole-M2.5" (layer "F.Cu")
    (at 101.5 98)
    (attr through_hole board_only)
    (fp_text reference "REF**" (at 0 0.5) (layer "F.SilkS") hide
        (effects (font (size 0.65 0.65) (thickness 0.12)))
    )
    (fp_text value "Mount-hole-M2.5" (at 0 -0.5) (layer "F.Fab") hide
        (effects (font (size 1 1) (thickness 0.15)))
    )
    (pad "1" thru_hole circle (at 0 0) (size 4.4 4.4) (drill 2.5) (layers "*.Cu" "*.Mask")
      (net 3 "GNDA"))
  )
	(footprint "sdi-mipi-bridge-footprints:R_0402_1005Metric" (layer "F.Cu")
    (at 149.25 129.75 90)
    (descr "Resistor SMD 0402")
    (tags "resistor SMD 0402")
    (property "Author" "Antmicro")
    (property "DNP" "DNP")
    (property "License" "Apache-2.0")
    (property "MPN" "CR0402-FX-1002GLF")
    (property "Manufacturer" "Bourns")
    (property "Sheetfile" "sdi-mipi-bridge.kicad_sch")
    (property "Sheetname" "")
    (property "Tolerance" "1%")
    (property "Val" "10k")
    (property "ki_description" "10k resistor in 0402 package with 1% tolerance")
    (attr exclude_from_pos_files)
    (fp_text reference "R106" (at -0.865 7.66 90) (layer "F.SilkS")
        (effects (font (size 0.65 0.65) (thickness 0.15)) (justify left bottom))
    )
    (fp_text value "R_10k_0402" (at 0 1.4 90) (layer "F.Fab") hide
        (effects (font (size 0.7 0.7) (thickness 0.15)) (justify left bottom))
    )
    (fp_text user "Author: Antmicro" (at -0.95 4.169 90) (layer "F.Fab") hide
        (effects (font (size 0.7 0.7) (thickness 0.15)) (justify left bottom))
    )
    (fp_text user "${REFERENCE}" (at -0.95 3.168 90) (layer "F.Fab") hide
        (effects (font (size 0.7 0.7) (thickness 0.15)) (justify left bottom))
    )
    (fp_text user "License: Apache-2.0" (at -0.95 5.169 90) (layer "F.Fab") hide
        (effects (font (size 0.7 0.7) (thickness 0.15)) (justify left bottom))
    )
    (fp_rect (start -0.93 -0.47) (end 0.93 0.47)
      (stroke (width 0.05) (type solid)) (fill none) (layer "F.CrtYd"))
    (fp_rect (start -0.5 -0.25) (end 0.5 0.25)
      (stroke (width 0.15) (type solid)) (fill none) (layer "F.Fab"))
    (pad "1" smd roundrect (at -0.485 0 90) (size 0.59 0.64) (layers "F.Cu" "F.Paste" "F.Mask") (roundrect_rratio 0.25)
      (net 24 "/~{RC_BYP}") (pintype "passive"))
    (pad "2" smd roundrect (at 0.485 0 90) (size 0.59 0.64) (layers "F.Cu" "F.Paste" "F.Mask") (roundrect_rratio 0.25)
      (net 76 "IO_VDD") (pintype "passive"))
  )
	(footprint "sdi-mipi-bridge-footprints:R_0402_1005Metric" (layer "F.Cu")
    (at 144.25 131.75 90)
    (descr "Resistor SMD 0402")
    (tags "resistor SMD 0402")
    (property "Author" "Antmicro")
    (property "DNP" "DNP")
    (property "License" "Apache-2.0")
    (property "MPN" "CR0402-FX-1002GLF")
    (property "Manufacturer" "Bourns")
    (property "Sheetfile" "sdi-mipi-bridge.kicad_sch")
    (property "Sheetname" "")
    (property "Tolerance" "1%")
    (property "Val" "10k")
    (property "ki_description" "10k resistor in 0402 package with 1% tolerance")
    (attr exclude_from_pos_files)
    (fp_text reference "R97" (at -5.75 0.4 90) (layer "F.SilkS")
        (effects (font (size 0.65 0.65) (thickness 0.15)) (justify left bottom))
    )
    (fp_text value "R_10k_0402" (at 0 1.4 90) (layer "F.Fab") hide
        (effects (font (size 0.7 0.7) (thickness 0.15)) (justify left bottom))
    )
    (fp_text user "License: Apache-2.0" (at -0.95 5.169 90) (layer "F.Fab") hide
        (effects (font (size 0.7 0.7) (thickness 0.15)) (justify left bottom))
    )
    (fp_text user "${REFERENCE}" (at -0.95 3.168 90) (layer "F.Fab") hide
        (effects (font (size 0.7 0.7) (thickness 0.15)) (justify left bottom))
    )
    (fp_text user "Author: Antmicro" (at -0.95 4.169 90) (layer "F.Fab") hide
        (effects (font (size 0.7 0.7) (thickness 0.15)) (justify left bottom))
    )
    (fp_rect (start -0.93 -0.47) (end 0.93 0.47)
      (stroke (width 0.05) (type solid)) (fill none) (layer "F.CrtYd"))
    (fp_rect (start -0.5 -0.25) (end 0.5 0.25)
      (stroke (width 0.15) (type solid)) (fill none) (layer "F.Fab"))
    (pad "1" smd roundrect (at -0.485 0 90) (size 0.59 0.64) (layers "F.Cu" "F.Paste" "F.Mask") (roundrect_rratio 0.25)
      (net 3 "GNDA") (pintype "passive"))
    (pad "2" smd roundrect (at 0.485 0 90) (size 0.59 0.64) (layers "F.Cu" "F.Paste" "F.Mask") (roundrect_rratio 0.25)
      (net 17 "/~{SMPTE_BYPASS}") (pintype "passive"))
  )
)
